# BASEBOARD_FAB2 (Tioga Pass) — schematic netlist excerpt (pin names and nets, part order shuffled) for the footprints in the layout excerpt that follows; sources: Cadence DE-HDL packaged netlist, KiCad conversion of Wiwynn_Tioga_Pass_MB.brd

C2U20  CAP_A  0.1UF 16V 10% X7R  pkg 0402V  page 108 : A = P12V ; B = GND
C2N17  CAP  10UF 6.3V 20% X6S  pkg 0603  page 130 : A = P3V3_STBY ; B = GND
R3P41  RES  75 1.0% CHIP  pkg 0402  page 92 : A = PVCCIO_CPU1 ; B = H_CPU1_THERMTRIP_G_N

(kicad_pcb
	(version 20260206)
	(generator "pcbnew")
	(generator_version "10.0")
	(general
		(thickness 1.6)
		(legacy_teardrops no)
	)
	(paper "A4")
	(title_block
		(title "Wiwynn_Tioga_Pass_MB.brd")
		(comment 1 "Tioga Pass / footprints 3866-3868 of 4770")
	)
	(layers
		(0 "F.Cu" signal "TOP")
		(4 "In1.Cu" signal "L2GND")
		(6 "In2.Cu" signal "L3")
		(8 "In3.Cu" signal "L4GND")
		(10 "In4.Cu" signal "L5")
		(12 "In5.Cu" signal "L6GND")
		(14 "In6.Cu" signal "L7VCC")
		(16 "In7.Cu" signal "L8VCC")
		(18 "In8.Cu" signal "L9GND")
		(20 "In9.Cu" signal "L10")
		(22 "In10.Cu" signal "L11GND")
		(24 "In11.Cu" signal "L12")
		(26 "In12.Cu" signal "L13GND")
		(2 "B.Cu" signal "BOTTOM")
		(9 "F.Adhes" user "F.Adhesive")
		(11 "B.Adhes" user "B.Adhesive")
		(13 "F.Paste" user "Package Geometry/Pastemask Top")
		(15 "B.Paste" user "Package Geometry/Pastemask Bottom")
		(5 "F.SilkS" user "Ref Des/Silkscreen Top")
		(7 "B.SilkS" user "Ref Des/Silkscreen Bottom")
		(1 "F.Mask" user "Board Geometry/Soldermask Top")
		(3 "B.Mask" user "Board Geometry/Soldermask Bottom")
		(17 "Dwgs.User" user "User.Drawings")
		(19 "Cmts.User" user "User.Comments")
		(21 "Eco1.User" user "User.Eco1")
		(23 "Eco2.User" user "User.Eco2")
		(25 "Edge.Cuts" user "Board Geometry/Outline")
		(27 "Margin" user)
		(31 "F.CrtYd" user "Package Geometry/Place Bound Top")
		(29 "B.CrtYd" user "Package Geometry/Place Bound Bottom")
		(35 "F.Fab" user "Ref Des/Assembly Top")
		(33 "B.Fab" user "Ref Des/Assembly Bottom")
	)
	(footprint ""
		(layer "B.Cu")
		(at 404.0124 -105.8545 180)
		(property "Reference" "C2N17"
			(at 0 0 0)
			(layer "B.SilkS")
			(hide yes)
			(effects
				(font
					(size 1.27 1.27)
				)
				(justify mirror)
			)
		)
		(property "Value" ""
			(at 0 0 0)
			(layer "B.Fab")
			(effects
				(font
					(size 1.27 1.27)
				)
				(justify mirror)
			)
		)
		(duplicate_pad_numbers_are_jumpers no)
		(fp_poly
			(pts
				(xy 0.4953 -0.2032) (xy -0.4953 -0.2032) (xy -0.4953 1.6002) (xy 0.4953 1.6002)
			)
			(stroke
				(width 0)
				(type default)
			)
			(fill no)
			(layer "B.CrtYd")
		)
		(fp_line
			(start 0.4953 1.6002)
			(end 0.4953 -0.2032)
			(stroke
				(width 0.1)
				(type default)
			)
			(layer "B.Fab")
		)
		(fp_line
			(start 0.4953 -0.2032)
			(end -0.4953 -0.2032)
			(stroke
				(width 0.1)
				(type default)
			)
			(layer "B.Fab")
		)
		(fp_line
			(start -0.4953 1.6002)
			(end 0.4953 1.6002)
			(stroke
				(width 0.1)
				(type default)
			)
			(layer "B.Fab")
		)
		(fp_line
			(start -0.4953 -0.2032)
			(end -0.4953 1.6002)
			(stroke
				(width 0.1)
				(type default)
			)
			(layer "B.Fab")
		)
		(pad "1" smd rect
			(at 0 0)
			(size 0.762 0.889)
			(layers "B.Cu" "B.Mask" "B.Paste")
			(net "P3V3_STBY")
		)
		(pad "2" smd rect
			(at 0 1.397)
			(size 0.762 0.889)
			(layers "B.Cu" "B.Mask" "B.Paste")
			(net "GND")
		)
		(zone
			(layer "B.Cu")
			(hatch none 0.5)
			(connect_pads
				(clearance 0)
			)
			(min_thickness 0.25)
			(keepout
				(tracks not_allowed)
				(vias allowed)
				(pads allowed)
				(copperpour not_allowed)
				(footprints allowed)
			)
			(placement
				(enabled no)
				(sheetname "")
			)
			(fill
				(thermal_gap 0.5)
				(thermal_bridge_width 0.5)
				(island_removal_mode 0)
			)
			(polygon
				(pts
					(xy 403.6314 -106.299) (xy 404.3934 -106.299) (xy 404.3934 -106.807) (xy 403.6314 -106.807)
				)
			)
		)
	)
	(footprint ""
		(layer "B.Cu")
		(at 373.6975 -55.88 -90)
		(property "Reference" "R3P41"
			(at 0 0 90)
			(layer "B.SilkS")
			(hide yes)
			(effects
				(font
					(size 1.27 1.27)
				)
				(justify mirror)
			)
		)
		(property "Value" ""
			(at 0 0 90)
			(layer "B.Fab")
			(effects
				(font
					(size 1.27 1.27)
				)
				(justify mirror)
			)
		)
		(duplicate_pad_numbers_are_jumpers no)
		(fp_poly
			(pts
				(xy 0.2794 -0.1016) (xy -0.2794 -0.1016) (xy -0.2794 0.9906) (xy 0.2794 0.9906)
			)
			(stroke
				(width 0)
				(type default)
			)
			(fill no)
			(layer "B.CrtYd")
		)
		(fp_line
			(start -0.2794 0.9906)
			(end -0.2794 -0.1016)
			(stroke
				(width 0.1)
				(type default)
			)
			(layer "B.Fab")
		)
		(fp_line
			(start 0.2794 0.9906)
			(end -0.2794 0.9906)
			(stroke
				(width 0.1)
				(type default)
			)
			(layer "B.Fab")
		)
		(fp_line
			(start -0.2794 -0.1016)
			(end 0.2794 -0.1016)
			(stroke
				(width 0.1)
				(type default)
			)
			(layer "B.Fab")
		)
		(fp_line
			(start 0.2794 -0.1016)
			(end 0.2794 0.9906)
			(stroke
				(width 0.1)
				(type default)
			)
			(layer "B.Fab")
		)
		(pad "1" smd rect
			(at 0 0 90)
			(size 0.508 0.508)
			(layers "B.Cu" "B.Mask" "B.Paste")
			(net "PVCCIO_CPU1")
		)
		(pad "2" smd rect
			(at 0 0.889 90)
			(size 0.508 0.508)
			(layers "B.Cu" "B.Mask" "B.Paste")
			(net "H_CPU1_THERMTRIP_G_N")
		)
		(zone
			(layer "B.Cu")
			(hatch none 0.5)
			(connect_pads
				(clearance 0)
			)
			(min_thickness 0.25)
			(keepout
				(tracks not_allowed)
				(vias allowed)
				(pads allowed)
				(copperpour not_allowed)
				(footprints allowed)
			)
			(placement
				(enabled no)
				(sheetname "")
			)
			(fill
				(thermal_gap 0.5)
				(thermal_bridge_width 0.5)
				(island_removal_mode 0)
			)
			(polygon
				(pts
					(xy 373.0625 -55.626) (xy 373.0625 -56.134) (xy 373.4435 -56.134) (xy 373.4435 -55.626)
				)
			)
		)
		(zone
			(layer "B.Cu")
			(hatch none 0.5)
			(connect_pads
				(clearance 0)
			)
			(min_thickness 0.25)
			(keepout
				(tracks allowed)
				(vias not_allowed)
				(pads allowed)
				(copperpour not_allowed)
				(footprints allowed)
			)
			(placement
				(enabled no)
				(sheetname "")
			)
			(fill
				(thermal_gap 0.5)
				(thermal_bridge_width 0.5)
				(island_removal_mode 0)
			)
			(polygon
				(pts
					(xy 373.4435 -55.626) (xy 373.4435 -56.134) (xy 373.0625 -56.134) (xy 373.0625 -55.626)
				)
			)
		)
	)
	(footprint ""
		(layer "B.Cu")
		(at 470.404444 -7.53872 -90)
		(property "Reference" "C2U20"
			(at 0 0 90)
			(layer "B.SilkS")
			(hide yes)
			(effects
				(font
					(size 1.27 1.27)
				)
				(justify mirror)
			)
		)
		(property "Value" ""
			(at 0 0 90)
			(layer "B.Fab")
			(effects
				(font
					(size 1.27 1.27)
				)
				(justify mirror)
			)
		)
		(duplicate_pad_numbers_are_jumpers no)
		(fp_poly
			(pts
				(xy -0.3048 -0.1016) (xy -0.3048 0.9906) (xy 0.3048 0.9906) (xy 0.3048 -0.1016)
			)
			(stroke
				(width 0)
				(type default)
			)
			(fill no)
			(layer "B.CrtYd")
		)
		(fp_line
			(start -0.3048 0.9906)
			(end -0.3048 -0.1016)
			(stroke
				(width 0.1)
				(type default)
			)
			(layer "B.Fab")
		)
		(fp_line
			(start 0.3048 0.9906)
			(end -0.3048 0.9906)
			(stroke
				(width 0.1)
				(type default)
			)
			(layer "B.Fab")
		)
		(fp_line
			(start -0.3048 -0.1016)
			(end 0.3048 -0.1016)
			(stroke
				(width 0.1)
				(type default)
			)
			(layer "B.Fab")
		)
		(fp_line
			(start 0.3048 -0.1016)
			(end 0.3048 0.9906)
			(stroke
				(width 0.1)
				(type default)
			)
			(layer "B.Fab")
		)
		(pad "1" smd rect
			(at 0 0 90)
			(size 0.508 0.508)
			(layers "B.Cu" "B.Mask" "B.Paste")
			(net "P12V")
		)
		(pad "2" smd rect
			(at 0 0.889 90)
			(size 0.508 0.508)
			(layers "B.Cu" "B.Mask" "B.Paste")
			(net "GND")
		)
		(zone
			(layer "B.Cu")
			(hatch none 0.5)
			(connect_pads
				(clearance 0)
			)
			(min_thickness 0.25)
			(keepout
				(tracks not_allowed)
				(vias allowed)
				(pads allowed)
				(copperpour not_allowed)
				(footprints allowed)
			)
			(placement
				(enabled no)
				(sheetname "")
			)
			(fill
				(thermal_gap 0.5)
				(thermal_bridge_width 0.5)
				(island_removal_mode 0)
			)
			(polygon
				(pts
					(xy 469.769444 -7.28472) (xy 469.769444 -7.79272) (xy 470.150444 -7.79272) (xy 470.150444 -7.28472)
				)
			)
		)
		(zone
			(layer "B.Cu")
			(hatch none 0.5)
			(connect_pads
				(clearance 0)
			)
			(min_thickness 0.25)
			(keepout
				(tracks allowed)
				(vias not_allowed)
				(pads allowed)
				(copperpour not_allowed)
				(footprints allowed)
			)
			(placement
				(enabled no)
				(sheetname "")
			)
			(fill
				(thermal_gap 0.5)
				(thermal_bridge_width 0.5)
				(island_removal_mode 0)
			)
			(polygon
				(pts
					(xy 470.150444 -7.28472) (xy 470.150444 -7.79272) (xy 469.769444 -7.79272) (xy 469.769444 -7.28472)
				)
			)
		)
	)
)
